(kicad_pcb
	(version 20260206)
	(generator "pcbnew")
	(generator_version "10.0")
	(general
		(thickness 1.6)
		(legacy_teardrops no)
	)
	(paper "A4")
	(title_block
		(title "04192023_DAF0TMB3IC0_F0TG_MB_C_brd_V02_OCP.brd")
		(comment 1 "Grand Teton / footprints 335-341 of 8354")
	)
	(layers
		(0 "F.Cu" signal "TOP")
		(4 "In1.Cu" signal "GND")
		(6 "In2.Cu" signal "IN1")
		(8 "In3.Cu" signal "GND1")
		(10 "In4.Cu" signal "IN2")
		(12 "In5.Cu" signal "GND2")
		(14 "In6.Cu" signal "IN3")
		(16 "In7.Cu" signal "GND3")
		(18 "In8.Cu" signal "VCC")
		(20 "In9.Cu" signal "VCC1")
		(22 "In10.Cu" signal "GND4")
		(24 "In11.Cu" signal "IN4")
		(26 "In12.Cu" signal "GND5")
		(28 "In13.Cu" signal "IN5")
		(30 "In14.Cu" signal "GND6")
		(32 "In15.Cu" signal "IN6")
		(34 "In16.Cu" signal "GND7")
		(2 "B.Cu" signal "BOTTOM")
		(9 "F.Adhes" user "F.Adhesive")
		(11 "B.Adhes" user "B.Adhesive")
		(13 "F.Paste" user "Package Geometry/Pastemask Top")
		(15 "B.Paste" user "Package Geometry/Pastemask Bottom")
		(5 "F.SilkS" user "Ref Des/Silkscreen Top")
		(7 "B.SilkS" user "Ref Des/Silkscreen Bottom")
		(1 "F.Mask" user "Board Geometry/Soldermask Top")
		(3 "B.Mask" user "Board Geometry/Soldermask Bottom")
		(17 "Dwgs.User" user "User.Drawings")
		(19 "Cmts.User" user "User.Comments")
		(21 "Eco1.User" user "User.Eco1")
		(23 "Eco2.User" user "User.Eco2")
		(25 "Edge.Cuts" user "Board Geometry/Outline")
		(27 "Margin" user)
		(31 "F.CrtYd" user "Package Geometry/Place Bound Top")
		(29 "B.CrtYd" user "Package Geometry/Place Bound Bottom")
		(35 "F.Fab" user "Ref Des/Assembly Top")
		(33 "B.Fab" user "Ref Des/Assembly Bottom")
	)
	(footprint ""
		(layer "F.Cu")
		(at 182.753 -100.294948 -90)
		(property "Reference" "R284"
			(at 0 0 270)
			(layer "F.SilkS")
			(hide yes)
			(effects
				(font
					(size 1.27 1.27)
				)
			)
		)
		(property "Value" ""
			(at 0 0 270)
			(layer "F.Fab")
			(effects
				(font
					(size 1.27 1.27)
				)
			)
		)
		(duplicate_pad_numbers_are_jumpers no)
		(fp_line
			(start -0.7874 0.4064)
			(end -0.7874 -0.4064)
			(stroke
				(width 0.1524)
				(type default)
			)
			(layer "F.SilkS")
		)
		(fp_line
			(start 0.7874 0.4064)
			(end -0.7874 0.4064)
			(stroke
				(width 0.1524)
				(type default)
			)
			(layer "F.SilkS")
		)
		(fp_line
			(start -0.7874 -0.4064)
			(end 0.7874 -0.4064)
			(stroke
				(width 0.1524)
				(type default)
			)
			(layer "F.SilkS")
		)
		(fp_line
			(start 0.7874 -0.4064)
			(end 0.7874 0.4064)
			(stroke
				(width 0.1524)
				(type default)
			)
			(layer "F.SilkS")
		)
		(fp_line
			(start -0.67945 0.3048)
			(end -0.67945 -0.305054)
			(stroke
				(width 0.1)
				(type default)
			)
			(layer "F.Fab")
		)
		(fp_line
			(start -0.12065 0.3048)
			(end -0.67945 0.3048)
			(stroke
				(width 0.1)
				(type default)
			)
			(layer "F.Fab")
		)
		(fp_line
			(start 0.120396 0.3048)
			(end 0.120396 0.2794)
			(stroke
				(width 0.1)
				(type default)
			)
			(layer "F.Fab")
		)
		(fp_line
			(start 0.67945 0.3048)
			(end 0.120396 0.3048)
			(stroke
				(width 0.1)
				(type default)
			)
			(layer "F.Fab")
		)
		(fp_line
			(start -0.12065 0.2794)
			(end -0.12065 0.3048)
			(stroke
				(width 0.1)
				(type default)
			)
			(layer "F.Fab")
		)
		(fp_line
			(start 0.120396 0.2794)
			(end -0.12065 0.2794)
			(stroke
				(width 0.1)
				(type default)
			)
			(layer "F.Fab")
		)
		(fp_line
			(start -0.12065 -0.2794)
			(end 0.12065 -0.2794)
			(stroke
				(width 0.1)
				(type default)
			)
			(layer "F.Fab")
		)
		(fp_line
			(start 0.12065 -0.2794)
			(end 0.12065 -0.3048)
			(stroke
				(width 0.1)
				(type default)
			)
			(layer "F.Fab")
		)
		(fp_line
			(start 0.12065 -0.3048)
			(end 0.67945 -0.3048)
			(stroke
				(width 0.1)
				(type default)
			)
			(layer "F.Fab")
		)
		(fp_line
			(start 0.67945 -0.3048)
			(end 0.67945 0.3048)
			(stroke
				(width 0.1)
				(type default)
			)
			(layer "F.Fab")
		)
		(fp_line
			(start -0.67945 -0.305054)
			(end -0.12065 -0.305054)
			(stroke
				(width 0.1)
				(type default)
			)
			(layer "F.Fab")
		)
		(fp_line
			(start -0.12065 -0.305054)
			(end -0.12065 -0.2794)
			(stroke
				(width 0.1)
				(type default)
			)
			(layer "F.Fab")
		)
		(pad "1" smd circle
			(at -0.40005 0 270)
			(size 0 0)
			(layers "F.Cu" "F.Mask" "F.Paste")
			(net "FM_PVDDCR_CPU0_P1_OCP_N")
		)
		(pad "2" smd circle
			(at 0.40005 0 270)
			(size 0 0)
			(layers "F.Cu" "F.Mask" "F.Paste")
			(net "PVDDCR_CPU0_P1_OCP_N")
		)
	)
	(footprint ""
		(layer "F.Cu")
		(at 100.046282 -342.604598 90)
		(property "Reference" "PC138"
			(at 0 0 90)
			(layer "F.SilkS")
			(hide yes)
			(effects
				(font
					(size 1.27 1.27)
				)
			)
		)
		(property "Value" ""
			(at 0 0 90)
			(layer "F.Fab")
			(effects
				(font
					(size 1.27 1.27)
				)
			)
		)
		(duplicate_pad_numbers_are_jumpers no)
		(fp_line
			(start 0.7874 -0.4064)
			(end 0.7874 0.4064)
			(stroke
				(width 0.1524)
				(type default)
			)
			(layer "F.SilkS")
		)
		(fp_line
			(start -0.7874 -0.4064)
			(end 0.7874 -0.4064)
			(stroke
				(width 0.1524)
				(type default)
			)
			(layer "F.SilkS")
		)
		(fp_line
			(start 0.7874 0.4064)
			(end 0.371602 0.4064)
			(stroke
				(width 0.1524)
				(type default)
			)
			(layer "F.SilkS")
		)
		(fp_line
			(start -0.263398 0.4064)
			(end -0.7874 0.4064)
			(stroke
				(width 0.1524)
				(type default)
			)
			(layer "F.SilkS")
		)
		(fp_line
			(start -0.7874 0.4064)
			(end -0.7874 -0.4064)
			(stroke
				(width 0.1524)
				(type default)
			)
			(layer "F.SilkS")
		)
		(fp_line
			(start -0.12065 -0.305054)
			(end -0.12065 -0.2794)
			(stroke
				(width 0.1)
				(type default)
			)
			(layer "F.Fab")
		)
		(fp_line
			(start -0.67945 -0.305054)
			(end -0.12065 -0.305054)
			(stroke
				(width 0.1)
				(type default)
			)
			(layer "F.Fab")
		)
		(fp_line
			(start 0.67945 -0.3048)
			(end 0.67945 0.3048)
			(stroke
				(width 0.1)
				(type default)
			)
			(layer "F.Fab")
		)
		(fp_line
			(start 0.12065 -0.3048)
			(end 0.67945 -0.3048)
			(stroke
				(width 0.1)
				(type default)
			)
			(layer "F.Fab")
		)
		(fp_line
			(start 0.12065 -0.2794)
			(end 0.12065 -0.3048)
			(stroke
				(width 0.1)
				(type default)
			)
			(layer "F.Fab")
		)
		(fp_line
			(start -0.12065 -0.2794)
			(end 0.12065 -0.2794)
			(stroke
				(width 0.1)
				(type default)
			)
			(layer "F.Fab")
		)
		(fp_line
			(start 0.120396 0.2794)
			(end -0.12065 0.2794)
			(stroke
				(width 0.1)
				(type default)
			)
			(layer "F.Fab")
		)
		(fp_line
			(start -0.12065 0.2794)
			(end -0.12065 0.3048)
			(stroke
				(width 0.1)
				(type default)
			)
			(layer "F.Fab")
		)
		(fp_line
			(start 0.67945 0.3048)
			(end 0.120396 0.3048)
			(stroke
				(width 0.1)
				(type default)
			)
			(layer "F.Fab")
		)
		(fp_line
			(start 0.120396 0.3048)
			(end 0.120396 0.2794)
			(stroke
				(width 0.1)
				(type default)
			)
			(layer "F.Fab")
		)
		(fp_line
			(start -0.12065 0.3048)
			(end -0.67945 0.3048)
			(stroke
				(width 0.1)
				(type default)
			)
			(layer "F.Fab")
		)
		(fp_line
			(start -0.67945 0.3048)
			(end -0.67945 -0.305054)
			(stroke
				(width 0.1)
				(type default)
			)
			(layer "F.Fab")
		)
		(pad "1" smd circle
			(at -0.40005 0 90)
			(size 0 0)
			(layers "F.Cu" "F.Mask" "F.Paste")
			(net "PVDDCR_CPU1_P1_VCC6")
		)
		(pad "2" smd circle
			(at 0.40005 0 90)
			(size 0 0)
			(layers "F.Cu" "F.Mask" "F.Paste")
			(net "GND")
		)
	)
	(footprint ""
		(layer "F.Cu")
		(at 372.937278 -147.568158 180)
		(property "Reference" "PR284"
			(at 0 0 180)
			(layer "F.SilkS")
			(hide yes)
			(effects
				(font
					(size 1.27 1.27)
				)
			)
		)
		(property "Value" ""
			(at 0 0 180)
			(layer "F.Fab")
			(effects
				(font
					(size 1.27 1.27)
				)
			)
		)
		(duplicate_pad_numbers_are_jumpers no)
		(fp_line
			(start 0.7874 0.4064)
			(end -0.7874 0.4064)
			(stroke
				(width 0.1524)
				(type default)
			)
			(layer "F.SilkS")
		)
		(fp_line
			(start 0.7874 -0.4064)
			(end 0.7874 0.4064)
			(stroke
				(width 0.1524)
				(type default)
			)
			(layer "F.SilkS")
		)
		(fp_line
			(start -0.7874 0.4064)
			(end -0.7874 -0.4064)
			(stroke
				(width 0.1524)
				(type default)
			)
			(layer "F.SilkS")
		)
		(fp_line
			(start -0.7874 -0.4064)
			(end 0.7874 -0.4064)
			(stroke
				(width 0.1524)
				(type default)
			)
			(layer "F.SilkS")
		)
		(fp_line
			(start 0.67945 0.3048)
			(end 0.120396 0.3048)
			(stroke
				(width 0.1)
				(type default)
			)
			(layer "F.Fab")
		)
		(fp_line
			(start 0.67945 -0.3048)
			(end 0.67945 0.3048)
			(stroke
				(width 0.1)
				(type default)
			)
			(layer "F.Fab")
		)
		(fp_line
			(start 0.12065 -0.2794)
			(end 0.12065 -0.3048)
			(stroke
				(width 0.1)
				(type default)
			)
			(layer "F.Fab")
		)
		(fp_line
			(start 0.12065 -0.3048)
			(end 0.67945 -0.3048)
			(stroke
				(width 0.1)
				(type default)
			)
			(layer "F.Fab")
		)
		(fp_line
			(start 0.120396 0.3048)
			(end 0.120396 0.2794)
			(stroke
				(width 0.1)
				(type default)
			)
			(layer "F.Fab")
		)
		(fp_line
			(start 0.120396 0.2794)
			(end -0.12065 0.2794)
			(stroke
				(width 0.1)
				(type default)
			)
			(layer "F.Fab")
		)
		(fp_line
			(start -0.12065 0.3048)
			(end -0.67945 0.3048)
			(stroke
				(width 0.1)
				(type default)
			)
			(layer "F.Fab")
		)
		(fp_line
			(start -0.12065 0.2794)
			(end -0.12065 0.3048)
			(stroke
				(width 0.1)
				(type default)
			)
			(layer "F.Fab")
		)
		(fp_line
			(start -0.12065 -0.2794)
			(end 0.12065 -0.2794)
			(stroke
				(width 0.1)
				(type default)
			)
			(layer "F.Fab")
		)
		(fp_line
			(start -0.12065 -0.305054)
			(end -0.12065 -0.2794)
			(stroke
				(width 0.1)
				(type default)
			)
			(layer "F.Fab")
		)
		(fp_line
			(start -0.67945 0.3048)
			(end -0.67945 -0.305054)
			(stroke
				(width 0.1)
				(type default)
			)
			(layer "F.Fab")
		)
		(fp_line
			(start -0.67945 -0.305054)
			(end -0.12065 -0.305054)
			(stroke
				(width 0.1)
				(type default)
			)
			(layer "F.Fab")
		)
		(pad "1" smd circle
			(at -0.40005 0 180)
			(size 0 0)
			(layers "F.Cu" "F.Mask" "F.Paste")
			(net "PVDD18_S5_P0")
		)
		(pad "2" smd circle
			(at 0.40005 0 180)
			(size 0 0)
			(layers "F.Cu" "F.Mask" "F.Paste")
			(net "SVID_PVDDCR_CPU0_P0_SVTI")
		)
	)
	(footprint ""
		(layer "F.Cu")
		(at 107.137454 -25.183592)
		(property "Reference" "C6091"
			(at 0 0 0)
			(layer "F.SilkS")
			(hide yes)
			(effects
				(font
					(size 1.27 1.27)
				)
			)
		)
		(property "Value" ""
			(at 0 0 0)
			(layer "F.Fab")
			(effects
				(font
					(size 1.27 1.27)
				)
			)
		)
		(duplicate_pad_numbers_are_jumpers no)
		(fp_line
			(start -0.7874 -0.4064)
			(end 0.7874 -0.4064)
			(stroke
				(width 0.1524)
				(type default)
			)
			(layer "F.SilkS")
		)
		(fp_line
			(start -0.7874 0.4064)
			(end -0.7874 -0.4064)
			(stroke
				(width 0.1524)
				(type default)
			)
			(layer "F.SilkS")
		)
		(fp_line
			(start 0.7874 -0.4064)
			(end 0.7874 0.4064)
			(stroke
				(width 0.1524)
				(type default)
			)
			(layer "F.SilkS")
		)
		(fp_line
			(start 0.7874 0.4064)
			(end -0.7874 0.4064)
			(stroke
				(width 0.1524)
				(type default)
			)
			(layer "F.SilkS")
		)
		(fp_line
			(start -0.67945 -0.305054)
			(end -0.12065 -0.305054)
			(stroke
				(width 0.1)
				(type default)
			)
			(layer "F.Fab")
		)
		(fp_line
			(start -0.67945 0.3048)
			(end -0.67945 -0.305054)
			(stroke
				(width 0.1)
				(type default)
			)
			(layer "F.Fab")
		)
		(fp_line
			(start -0.12065 -0.305054)
			(end -0.12065 -0.2794)
			(stroke
				(width 0.1)
				(type default)
			)
			(layer "F.Fab")
		)
		(fp_line
			(start -0.12065 -0.2794)
			(end 0.12065 -0.2794)
			(stroke
				(width 0.1)
				(type default)
			)
			(layer "F.Fab")
		)
		(fp_line
			(start -0.12065 0.2794)
			(end -0.12065 0.3048)
			(stroke
				(width 0.1)
				(type default)
			)
			(layer "F.Fab")
		)
		(fp_line
			(start -0.12065 0.3048)
			(end -0.67945 0.3048)
			(stroke
				(width 0.1)
				(type default)
			)
			(layer "F.Fab")
		)
		(fp_line
			(start 0.120396 0.2794)
			(end -0.12065 0.2794)
			(stroke
				(width 0.1)
				(type default)
			)
			(layer "F.Fab")
		)
		(fp_line
			(start 0.120396 0.3048)
			(end 0.120396 0.2794)
			(stroke
				(width 0.1)
				(type default)
			)
			(layer "F.Fab")
		)
		(fp_line
			(start 0.12065 -0.3048)
			(end 0.67945 -0.3048)
			(stroke
				(width 0.1)
				(type default)
			)
			(layer "F.Fab")
		)
		(fp_line
			(start 0.12065 -0.2794)
			(end 0.12065 -0.3048)
			(stroke
				(width 0.1)
				(type default)
			)
			(layer "F.Fab")
		)
		(fp_line
			(start 0.67945 -0.3048)
			(end 0.67945 0.3048)
			(stroke
				(width 0.1)
				(type default)
			)
			(layer "F.Fab")
		)
		(fp_line
			(start 0.67945 0.3048)
			(end 0.120396 0.3048)
			(stroke
				(width 0.1)
				(type default)
			)
			(layer "F.Fab")
		)
		(pad "1" smd circle
			(at -0.40005 0)
			(size 0 0)
			(layers "F.Cu" "F.Mask" "F.Paste")
			(net "XTAL_USB_CPU0_HUB2_XIN")
		)
		(pad "2" smd circle
			(at 0.40005 0)
			(size 0 0)
			(layers "F.Cu" "F.Mask" "F.Paste")
			(net "GND")
		)
	)
	(footprint ""
		(layer "F.Cu")
		(at 200.952608 -115.657376)
		(property "Reference" "R6112"
			(at 0 0 0)
			(layer "F.SilkS")
			(hide yes)
			(effects
				(font
					(size 1.27 1.27)
				)
			)
		)
		(property "Value" ""
			(at 0 0 0)
			(layer "F.Fab")
			(effects
				(font
					(size 1.27 1.27)
				)
			)
		)
		(duplicate_pad_numbers_are_jumpers no)
		(fp_line
			(start -0.7874 -0.4064)
			(end 0.7874 -0.4064)
			(stroke
				(width 0.1524)
				(type default)
			)
			(layer "F.SilkS")
		)
		(fp_line
			(start -0.7874 0.4064)
			(end -0.7874 -0.4064)
			(stroke
				(width 0.1524)
				(type default)
			)
			(layer "F.SilkS")
		)
		(fp_line
			(start 0.7874 -0.4064)
			(end 0.7874 0.4064)
			(stroke
				(width 0.1524)
				(type default)
			)
			(layer "F.SilkS")
		)
		(fp_line
			(start 0.7874 0.4064)
			(end -0.7874 0.4064)
			(stroke
				(width 0.1524)
				(type default)
			)
			(layer "F.SilkS")
		)
		(fp_line
			(start -0.67945 -0.305054)
			(end -0.12065 -0.305054)
			(stroke
				(width 0.1)
				(type default)
			)
			(layer "F.Fab")
		)
		(fp_line
			(start -0.67945 0.3048)
			(end -0.67945 -0.305054)
			(stroke
				(width 0.1)
				(type default)
			)
			(layer "F.Fab")
		)
		(fp_line
			(start -0.12065 -0.305054)
			(end -0.12065 -0.2794)
			(stroke
				(width 0.1)
				(type default)
			)
			(layer "F.Fab")
		)
		(fp_line
			(start -0.12065 -0.2794)
			(end 0.12065 -0.2794)
			(stroke
				(width 0.1)
				(type default)
			)
			(layer "F.Fab")
		)
		(fp_line
			(start -0.12065 0.2794)
			(end -0.12065 0.3048)
			(stroke
				(width 0.1)
				(type default)
			)
			(layer "F.Fab")
		)
		(fp_line
			(start -0.12065 0.3048)
			(end -0.67945 0.3048)
			(stroke
				(width 0.1)
				(type default)
			)
			(layer "F.Fab")
		)
		(fp_line
			(start 0.120396 0.2794)
			(end -0.12065 0.2794)
			(stroke
				(width 0.1)
				(type default)
			)
			(layer "F.Fab")
		)
		(fp_line
			(start 0.120396 0.3048)
			(end 0.120396 0.2794)
			(stroke
				(width 0.1)
				(type default)
			)
			(layer "F.Fab")
		)
		(fp_line
			(start 0.12065 -0.3048)
			(end 0.67945 -0.3048)
			(stroke
				(width 0.1)
				(type default)
			)
			(layer "F.Fab")
		)
		(fp_line
			(start 0.12065 -0.2794)
			(end 0.12065 -0.3048)
			(stroke
				(width 0.1)
				(type default)
			)
			(layer "F.Fab")
		)
		(fp_line
			(start 0.67945 -0.3048)
			(end 0.67945 0.3048)
			(stroke
				(width 0.1)
				(type default)
			)
			(layer "F.Fab")
		)
		(fp_line
			(start 0.67945 0.3048)
			(end 0.120396 0.3048)
			(stroke
				(width 0.1)
				(type default)
			)
			(layer "F.Fab")
		)
		(pad "1" smd circle
			(at -0.40005 0)
			(size 0 0)
			(layers "F.Cu" "F.Mask" "F.Paste")
			(net "RST_PERST_CPU0_SWB_N")
		)
		(pad "2" smd circle
			(at 0.40005 0)
			(size 0 0)
			(layers "F.Cu" "F.Mask" "F.Paste")
			(net "RST_PERST_CPU0_SWB_R_N")
		)
	)
	(footprint ""
		(layer "F.Cu")
		(at 32.23514 -346.87129 -90)
		(property "Reference" "PC625_4"
			(at 0 0 270)
			(layer "F.SilkS")
			(hide yes)
			(effects
				(font
					(size 1.27 1.27)
				)
			)
		)
		(property "Value" ""
			(at 0 0 270)
			(layer "F.Fab")
			(effects
				(font
					(size 1.27 1.27)
				)
			)
		)
		(duplicate_pad_numbers_are_jumpers no)
		(fp_line
			(start -0.7874 0.4064)
			(end -0.7874 -0.4064)
			(stroke
				(width 0.1524)
				(type default)
			)
			(layer "F.SilkS")
		)
		(fp_line
			(start 0.7874 0.4064)
			(end -0.7874 0.4064)
			(stroke
				(width 0.1524)
				(type default)
			)
			(layer "F.SilkS")
		)
		(fp_line
			(start -0.7874 -0.4064)
			(end 0.7874 -0.4064)
			(stroke
				(width 0.1524)
				(type default)
			)
			(layer "F.SilkS")
		)
		(fp_line
			(start 0.7874 -0.4064)
			(end 0.7874 0.4064)
			(stroke
				(width 0.1524)
				(type default)
			)
			(layer "F.SilkS")
		)
		(fp_line
			(start -0.67945 0.3048)
			(end -0.67945 -0.305054)
			(stroke
				(width 0.1)
				(type default)
			)
			(layer "F.Fab")
		)
		(fp_line
			(start -0.12065 0.3048)
			(end -0.67945 0.3048)
			(stroke
				(width 0.1)
				(type default)
			)
			(layer "F.Fab")
		)
		(fp_line
			(start 0.120396 0.3048)
			(end 0.120396 0.2794)
			(stroke
				(width 0.1)
				(type default)
			)
			(layer "F.Fab")
		)
		(fp_line
			(start 0.67945 0.3048)
			(end 0.120396 0.3048)
			(stroke
				(width 0.1)
				(type default)
			)
			(layer "F.Fab")
		)
		(fp_line
			(start -0.12065 0.2794)
			(end -0.12065 0.3048)
			(stroke
				(width 0.1)
				(type default)
			)
			(layer "F.Fab")
		)
		(fp_line
			(start 0.120396 0.2794)
			(end -0.12065 0.2794)
			(stroke
				(width 0.1)
				(type default)
			)
			(layer "F.Fab")
		)
		(fp_line
			(start -0.12065 -0.2794)
			(end 0.12065 -0.2794)
			(stroke
				(width 0.1)
				(type default)
			)
			(layer "F.Fab")
		)
		(fp_line
			(start 0.12065 -0.2794)
			(end 0.12065 -0.3048)
			(stroke
				(width 0.1)
				(type default)
			)
			(layer "F.Fab")
		)
		(fp_line
			(start 0.12065 -0.3048)
			(end 0.67945 -0.3048)
			(stroke
				(width 0.1)
				(type default)
			)
			(layer "F.Fab")
		)
		(fp_line
			(start 0.67945 -0.3048)
			(end 0.67945 0.3048)
			(stroke
				(width 0.1)
				(type default)
			)
			(layer "F.Fab")
		)
		(fp_line
			(start -0.67945 -0.305054)
			(end -0.12065 -0.305054)
			(stroke
				(width 0.1)
				(type default)
			)
			(layer "F.Fab")
		)
		(fp_line
			(start -0.12065 -0.305054)
			(end -0.12065 -0.2794)
			(stroke
				(width 0.1)
				(type default)
			)
			(layer "F.Fab")
		)
		(pad "1" smd circle
			(at -0.40005 0 270)
			(size 0 0)
			(layers "F.Cu" "F.Mask" "F.Paste")
			(net "SW_P12V_AUX_PVDDIO_P1_FLT")
		)
		(pad "2" smd circle
			(at 0.40005 0 270)
			(size 0 0)
			(layers "F.Cu" "F.Mask" "F.Paste")
			(net "GND")
		)
	)
	(footprint ""
		(layer "F.Cu")
		(at 49.342294 -16.099536 90)
		(property "Reference" "C702"
			(at 0 0 90)
			(layer "F.SilkS")
			(hide yes)
			(effects
				(font
					(size 1.27 1.27)
				)
			)
		)
		(property "Value" ""
			(at 0 0 90)
			(layer "F.Fab")
			(effects
				(font
					(size 1.27 1.27)
				)
			)
		)
		(duplicate_pad_numbers_are_jumpers no)
		(fp_line
			(start 0.299974 -0.150114)
			(end 0.299974 0.150114)
			(stroke
				(width 0.1)
				(type default)
			)
			(layer "F.Fab")
		)
		(fp_line
			(start -0.299974 -0.150114)
			(end 0.299974 -0.150114)
			(stroke
				(width 0.1)
				(type default)
			)
			(layer "F.Fab")
		)
		(fp_line
			(start 0.299974 0.150114)
			(end -0.299974 0.150114)
			(stroke
				(width 0.1)
				(type default)
			)
			(layer "F.Fab")
		)
		(fp_line
			(start -0.299974 0.150114)
			(end -0.299974 -0.150114)
			(stroke
				(width 0.1)
				(type default)
			)
			(layer "F.Fab")
		)
		(pad "1" smd rect
			(at -0.2667 0 90)
			(size 0.3048 0.381)
			(layers "F.Cu" "F.Mask" "F.Paste")
			(net "P5E_CPU1_G1_TX_C_DN<3>")
		)
		(pad "2" smd rect
			(at 0.2667 0 90)
			(size 0.3048 0.381)
			(layers "F.Cu" "F.Mask" "F.Paste")
			(net "P5E_CPU1_G1_TX_DN<3>")
		)
	)
)
